# SCM (Grand Teton) — schematic netlist excerpt (pin names and nets, part order shuffled) for the footprints in the layout excerpt that follows; sources: Cadence DE-HDL packaged netlist, KiCad conversion of 12092022_DA0F0TMDCD0_F0T_Management_Board_D_brd_V3_OCP.brd

C80  Q_CAP  1UF 25V 10% X6S  pkg C0402  page 17 : A = P1V8_STBY_RC_VCC18A ; B = GND
R559  Q_RES  33.2 1% CHIP  pkg 0402LF  page 25 : A = SPI_BMC_BT_WP0_N_R ; B = FLASH_LATCH_Q_N_R2

(kicad_pcb
	(version 20260206)
	(generator "pcbnew")
	(generator_version "10.0")
	(general
		(thickness 1.6)
		(legacy_teardrops no)
	)
	(paper "A4")
	(title_block
		(title "12092022_DA0F0TMDCD0_F0T_Management_Board_D_brd_V3_OCP.brd")
		(comment 1 "Grand Teton / footprints 227-228 of 1440")
	)
	(layers
		(0 "F.Cu" signal "TOP")
		(4 "In1.Cu" signal "GND")
		(6 "In2.Cu" signal "IN1")
		(8 "In3.Cu" signal "GND1")
		(10 "In4.Cu" signal "IN2")
		(12 "In5.Cu" signal "VCC")
		(14 "In6.Cu" signal "VCC1")
		(16 "In7.Cu" signal "IN3")
		(18 "In8.Cu" signal "GND2")
		(20 "In9.Cu" signal "IN4")
		(22 "In10.Cu" signal "GND3")
		(2 "B.Cu" signal "BOTTOM")
		(9 "F.Adhes" user "F.Adhesive")
		(11 "B.Adhes" user "B.Adhesive")
		(13 "F.Paste" user "Package Geometry/Pastemask Top")
		(15 "B.Paste" user "Package Geometry/Pastemask Bottom")
		(5 "F.SilkS" user "Ref Des/Silkscreen Top")
		(7 "B.SilkS" user "Ref Des/Silkscreen Bottom")
		(1 "F.Mask" user "Board Geometry/Soldermask Top")
		(3 "B.Mask" user "Board Geometry/Soldermask Bottom")
		(17 "Dwgs.User" user "User.Drawings")
		(19 "Cmts.User" user "User.Comments")
		(21 "Eco1.User" user "User.Eco1")
		(23 "Eco2.User" user "User.Eco2")
		(25 "Edge.Cuts" user "Board Geometry/Outline")
		(27 "Margin" user)
		(31 "F.CrtYd" user "Package Geometry/Place Bound Top")
		(29 "B.CrtYd" user "Package Geometry/Place Bound Bottom")
		(35 "F.Fab" user "Ref Des/Assembly Top")
		(33 "B.Fab" user "Ref Des/Assembly Bottom")
	)
	(footprint ""
		(layer "F.Cu")
		(at 69.097398 -62.725808 -90)
		(property "Reference" "C80"
			(at 0 0 270)
			(layer "F.SilkS")
			(hide yes)
			(effects
				(font
					(size 1.27 1.27)
				)
			)
		)
		(property "Value" ""
			(at 0 0 270)
			(layer "F.Fab")
			(effects
				(font
					(size 1.27 1.27)
				)
			)
		)
		(duplicate_pad_numbers_are_jumpers no)
		(fp_line
			(start -0.7874 0.4064)
			(end -0.7874 -0.4064)
			(stroke
				(width 0.1524)
				(type default)
			)
			(layer "F.SilkS")
		)
		(fp_line
			(start 0.7874 0.4064)
			(end -0.7874 0.4064)
			(stroke
				(width 0.1524)
				(type default)
			)
			(layer "F.SilkS")
		)
		(fp_line
			(start -0.7874 -0.4064)
			(end 0.7874 -0.4064)
			(stroke
				(width 0.1524)
				(type default)
			)
			(layer "F.SilkS")
		)
		(fp_line
			(start 0.7874 -0.4064)
			(end 0.7874 0.4064)
			(stroke
				(width 0.1524)
				(type default)
			)
			(layer "F.SilkS")
		)
		(fp_line
			(start -0.67945 0.3048)
			(end -0.67945 -0.305054)
			(stroke
				(width 0.1)
				(type default)
			)
			(layer "F.Fab")
		)
		(fp_line
			(start -0.12065 0.3048)
			(end -0.67945 0.3048)
			(stroke
				(width 0.1)
				(type default)
			)
			(layer "F.Fab")
		)
		(fp_line
			(start 0.120396 0.3048)
			(end 0.120396 0.2794)
			(stroke
				(width 0.1)
				(type default)
			)
			(layer "F.Fab")
		)
		(fp_line
			(start 0.67945 0.3048)
			(end 0.120396 0.3048)
			(stroke
				(width 0.1)
				(type default)
			)
			(layer "F.Fab")
		)
		(fp_line
			(start -0.12065 0.2794)
			(end -0.12065 0.3048)
			(stroke
				(width 0.1)
				(type default)
			)
			(layer "F.Fab")
		)
		(fp_line
			(start 0.120396 0.2794)
			(end -0.12065 0.2794)
			(stroke
				(width 0.1)
				(type default)
			)
			(layer "F.Fab")
		)
		(fp_line
			(start -0.12065 -0.2794)
			(end 0.12065 -0.2794)
			(stroke
				(width 0.1)
				(type default)
			)
			(layer "F.Fab")
		)
		(fp_line
			(start 0.12065 -0.2794)
			(end 0.12065 -0.3048)
			(stroke
				(width 0.1)
				(type default)
			)
			(layer "F.Fab")
		)
		(fp_line
			(start 0.12065 -0.3048)
			(end 0.67945 -0.3048)
			(stroke
				(width 0.1)
				(type default)
			)
			(layer "F.Fab")
		)
		(fp_line
			(start 0.67945 -0.3048)
			(end 0.67945 0.3048)
			(stroke
				(width 0.1)
				(type default)
			)
			(layer "F.Fab")
		)
		(fp_line
			(start -0.67945 -0.305054)
			(end -0.12065 -0.305054)
			(stroke
				(width 0.1)
				(type default)
			)
			(layer "F.Fab")
		)
		(fp_line
			(start -0.12065 -0.305054)
			(end -0.12065 -0.2794)
			(stroke
				(width 0.1)
				(type default)
			)
			(layer "F.Fab")
		)
		(pad "1" smd circle
			(at -0.40005 0 270)
			(size 0 0)
			(layers "F.Cu" "F.Mask" "F.Paste")
			(net "P1V8_STBY_RC_VCC18A")
		)
		(pad "2" smd circle
			(at 0.40005 0 270)
			(size 0 0)
			(layers "F.Cu" "F.Mask" "F.Paste")
			(net "GND")
		)
	)
	(footprint ""
		(layer "F.Cu")
		(at 45.085 -83.6168)
		(property "Reference" "R559"
			(at 0 0 0)
			(layer "F.SilkS")
			(hide yes)
			(effects
				(font
					(size 1.27 1.27)
				)
			)
		)
		(property "Value" ""
			(at 0 0 0)
			(layer "F.Fab")
			(effects
				(font
					(size 1.27 1.27)
				)
			)
		)
		(duplicate_pad_numbers_are_jumpers no)
		(fp_line
			(start -0.7874 -0.4064)
			(end 0.7874 -0.4064)
			(stroke
				(width 0.1524)
				(type default)
			)
			(layer "F.SilkS")
		)
		(fp_line
			(start -0.7874 0.4064)
			(end -0.7874 -0.4064)
			(stroke
				(width 0.1524)
				(type default)
			)
			(layer "F.SilkS")
		)
		(fp_line
			(start 0.7874 -0.4064)
			(end 0.7874 0.4064)
			(stroke
				(width 0.1524)
				(type default)
			)
			(layer "F.SilkS")
		)
		(fp_line
			(start 0.7874 0.4064)
			(end -0.7874 0.4064)
			(stroke
				(width 0.1524)
				(type default)
			)
			(layer "F.SilkS")
		)
		(fp_line
			(start -0.67945 -0.305054)
			(end -0.12065 -0.305054)
			(stroke
				(width 0.1)
				(type default)
			)
			(layer "F.Fab")
		)
		(fp_line
			(start -0.67945 0.3048)
			(end -0.67945 -0.305054)
			(stroke
				(width 0.1)
				(type default)
			)
			(layer "F.Fab")
		)
		(fp_line
			(start -0.12065 -0.305054)
			(end -0.12065 -0.2794)
			(stroke
				(width 0.1)
				(type default)
			)
			(layer "F.Fab")
		)
		(fp_line
			(start -0.12065 -0.2794)
			(end 0.12065 -0.2794)
			(stroke
				(width 0.1)
				(type default)
			)
			(layer "F.Fab")
		)
		(fp_line
			(start -0.12065 0.2794)
			(end -0.12065 0.3048)
			(stroke
				(width 0.1)
				(type default)
			)
			(layer "F.Fab")
		)
		(fp_line
			(start -0.12065 0.3048)
			(end -0.67945 0.3048)
			(stroke
				(width 0.1)
				(type default)
			)
			(layer "F.Fab")
		)
		(fp_line
			(start 0.120396 0.2794)
			(end -0.12065 0.2794)
			(stroke
				(width 0.1)
				(type default)
			)
			(layer "F.Fab")
		)
		(fp_line
			(start 0.120396 0.3048)
			(end 0.120396 0.2794)
			(stroke
				(width 0.1)
				(type default)
			)
			(layer "F.Fab")
		)
		(fp_line
			(start 0.12065 -0.3048)
			(end 0.67945 -0.3048)
			(stroke
				(width 0.1)
				(type default)
			)
			(layer "F.Fab")
		)
		(fp_line
			(start 0.12065 -0.2794)
			(end 0.12065 -0.3048)
			(stroke
				(width 0.1)
				(type default)
			)
			(layer "F.Fab")
		)
		(fp_line
			(start 0.67945 -0.3048)
			(end 0.67945 0.3048)
			(stroke
				(width 0.1)
				(type default)
			)
			(layer "F.Fab")
		)
		(fp_line
			(start 0.67945 0.3048)
			(end 0.120396 0.3048)
			(stroke
				(width 0.1)
				(type default)
			)
			(layer "F.Fab")
		)
		(pad "1" smd circle
			(at -0.40005 0)
			(size 0 0)
			(layers "F.Cu" "F.Mask" "F.Paste")
			(net "SPI_BMC_BT_WP0_N_R")
		)
		(pad "2" smd circle
			(at 0.40005 0)
			(size 0 0)
			(layers "F.Cu" "F.Mask" "F.Paste")
			(net "FLASH_LATCH_Q_N_R2")
		)
	)
)
